# S9S_MB_2U (Grand Teton) — schematic parts with pin connectivity, parts 1598–1598 of 6093; source: Cadence DE-HDL packaged netlist (pstxprt.dat, pstxnet.dat, pstchip.dat)

J5  SCONN288_ADR50017P130CC  SCONN288_ADR50017-P130CC IO  pkg DDR288S_1-1VXB  page 86
  1  VIN_BULK0  POWER  = P12V_S3_AUX_CPU0_NVDIMM
  2  RFU0  TRI  = TP_CHC_CPU0_DIMM1_FRU_0
  3  VIN_MGMT  POWER  = P3V3_AUX
  4  HSCL  IN  = I3C_SPD_DDRABCD_CPU0_LVC1_SCL_4
  5  HSDA  BI  = I3C_SPD_DDRABCD_CPU0_LVC1_SDA
  6  VSS0  POWER  = GND
  7  DQ0_A  BI  = M_C_CPU0_SA_DQ<0>
  8  VSS1  POWER  = GND
  9  DQ1_A  BI  = M_C_CPU0_SA_DQ<1>
  10  VSS2  POWER  = GND
  11  DQS0_A_T  BI  = M_C_CPU0_SA_DQS_DP<0>
  12  DQS0_A_C  BI  = M_C_CPU0_SA_DQS_DN<0>
  13  VSS3  POWER  = GND
  14  DQ4_A  BI  = M_C_CPU0_SA_DQ<4>
  15  VSS4  POWER  = GND
  16  DQ5_A  BI  = M_C_CPU0_SA_DQ<5>
  17  VSS5  POWER  = GND
  18  DQ8_A  BI  = M_C_CPU0_SA_DQ<8>
  19  VSS6  POWER  = GND
  20  DQ9_A  BI  = M_C_CPU0_SA_DQ<9>
  21  VSS7  POWER  = GND
  22  DQS1_A_T  BI  = M_C_CPU0_SA_DQS_DP<1>
  23  DQS1_A_C  BI  = M_C_CPU0_SA_DQS_DN<1>
  24  VSS8  POWER  = GND
  25  DQ12_A  BI  = M_C_CPU0_SA_DQ<12>
  26  VSS9  POWER  = GND
  27  DQ13_A  BI  = M_C_CPU0_SA_DQ<13>
  28  VSS10  POWER  = GND
  29  DQ16_A  BI  = M_C_CPU0_SA_DQ<16>
  30  VSS11  POWER  = GND
  31  DQ17_A  BI  = M_C_CPU0_SA_DQ<17>
  32  VSS12  POWER  = GND
  33  DQS2_A_T  BI  = M_C_CPU0_SA_DQS_DP<2>
  34  DQS2_A_C  BI  = M_C_CPU0_SA_DQS_DN<2>
  35  VSS13  POWER  = GND
  36  DQ20_A  BI  = M_C_CPU0_SA_DQ<20>
  37  VSS14  POWER  = GND
  38  DQ21_A  BI  = M_C_CPU0_SA_DQ<21>
  39  VSS15  POWER  = GND
  40  DQ24_A  BI  = M_C_CPU0_SA_DQ<24>
  41  VSS16  POWER  = GND
  42  DQ25_A  BI  = M_C_CPU0_SA_DQ<25>
  43  VSS17  POWER  = GND
  44  DQS3_A_T  BI  = M_C_CPU0_SA_DQS_DP<3>
  45  DQS3_A_C  BI  = M_C_CPU0_SA_DQS_DN<3>
  46  VSS18  POWER  = GND
  47  DQ28_A  BI  = M_C_CPU0_SA_DQ<28>
  48  VSS19  POWER  = GND
  49  DQ29_A  BI  = M_C_CPU0_SA_DQ<29>
  50  VSS20  POWER  = GND
  51  CB0_A  BI  = M_C_CPU0_SA_CB<0>
  52  VSS21  POWER  = GND
  53  CB1_A  BI  = M_C_CPU0_SA_CB<1>
  54  VSS22  POWER  = GND
  55  DQS4_A_T  BI  = M_C_CPU0_SA_DQS_DP<4>
  56  DQS4_A_C  BI  = M_C_CPU0_SA_DQS_DN<4>
  57  VSS23  POWER  = GND
  58  CB4_A  BI  = M_C_CPU0_SA_CB<4>
  59  VSS24  POWER  = GND
  60  CB5_A  BI  = M_C_CPU0_SA_CB<5>
  61  VSS25  POWER  = GND
  62  ALERT_N  OUT  = M_C_CPU0_ALERT_N
  63  VSS26  POWER  = GND
  64  CS0_A_N  IN  = M_C_CPU0_SA_CS_N<0>
  65  VSS27  POWER  = GND
  66  CA0_A  IN  = M_C_CPU0_SA_CA<0>
  67  VSS28  POWER  = GND
  68  CA2_A  IN  = M_C_CPU0_SA_CA<2>
  69  VSS29  POWER  = GND
  70  CA4_A  IN  = M_C_CPU0_SA_CA<4>
  71  VSS30  POWER  = GND
  72  CA6_A  IN  = M_C_CPU0_SA_CA<6>
  73  VSS31  POWER  = GND
  74  PAR_A  IN  = M_C_CPU0_SA_PAR
  75  VSS32  POWER  = GND
  76  CA0_B  IN  = M_C_CPU0_SB_CA<0>
  77  VSS33  POWER  = GND
  78  CA2_B  IN  = M_C_CPU0_SB_CA<2>
  79  VSS34  POWER  = GND
  80  CA4_B  IN  = M_C_CPU0_SB_CA<4>
  81  VSS35  POWER  = GND
  82  CA6_B  IN  = M_C_CPU0_SB_CA<6>
  83  VSS36  POWER  = GND
  84  CS0_B_N  IN  = M_C_CPU0_SB_CS_N<0>
  85  VSS37  POWER  = GND
  86  \lbd||rsp_a_n\  OUT  = M_C_CPU0_SA_RSP<0>
  87  \lbs||rsp_b_n\  OUT  = M_C_CPU0_SB_RSP<0>
  88  VSS38  POWER  = GND
  89  CB4_B  BI  = M_C_CPU0_SB_CB<4>
  90  VSS39  POWER  = GND
  91  CB5_B  BI  = M_C_CPU0_SB_CB<5>
  92  VSS40  POWER  = GND
  93  \dqs9_b_t||tdqs9_b_t||dbi4_b_n\  BI  = M_C_CPU0_SB_DQS_DP<9>
  94  \dqs9_b_c||tdqs9_b_c\  BI  = M_C_CPU0_SB_DQS_DN<9>
  95  VSS41  POWER  = GND
  96  CB0_B  BI  = M_C_CPU0_SB_CB<0>
  97  VSS42  POWER  = GND
  98  CB1_B  BI  = M_C_CPU0_SB_CB<1>
  99  VSS43  POWER  = GND
  100  DQ0_B  BI  = M_C_CPU0_SB_DQ<0>
  101  VSS44  POWER  = GND
  102  DQ1_B  BI  = M_C_CPU0_SB_DQ<1>
  103  VSS45  POWER  = GND
  104  DQS0_B_T  BI  = M_C_CPU0_SB_DQS_DP<0>
  105  DQS0_B_C  BI  = M_C_CPU0_SB_DQS_DN<0>
  106  VSS46  POWER  = GND
  107  DQ4_B  BI  = M_C_CPU0_SB_DQ<4>
  108  VSS47  POWER  = GND
  109  DQ5_B  BI  = M_C_CPU0_SB_DQ<5>
  110  VSS48  POWER  = GND
  111  DQ8_B  BI  = M_C_CPU0_SB_DQ<8>
  112  VSS49  POWER  = GND
  113  DQ9_B  BI  = M_C_CPU0_SB_DQ<9>
  114  VSS50  POWER  = GND
  115  DQS1_B_T  BI  = M_C_CPU0_SB_DQS_DP<1>
  116  DQS1_B_C  BI  = M_C_CPU0_SB_DQS_DN<1>
  117  VSS51  POWER  = GND
  118  DQ12_B  BI  = M_C_CPU0_SB_DQ<12>
  119  VSS52  POWER  = GND
  120  DQ13_B  BI  = M_C_CPU0_SB_DQ<13>
  121  VSS53  POWER  = GND
  122  DQ16_B  BI  = M_C_CPU0_SB_DQ<16>
  123  VSS54  POWER  = GND
  124  DQ17_B  BI  = M_C_CPU0_SB_DQ<17>
  125  VSS55  POWER  = GND
  126  DQS2_B_T  BI  = M_C_CPU0_SB_DQS_DP<2>
  127  DQS2_B_C  BI  = M_C_CPU0_SB_DQS_DN<2>
  128  VSS56  POWER  = GND
  129  DQ20_B  BI  = M_C_CPU0_SB_DQ<20>
  130  VSS57  POWER  = GND
  131  DQ21_B  BI  = M_C_CPU0_SB_DQ<21>
  132  VSS58  POWER  = GND
  133  DQ24_B  BI  = M_C_CPU0_SB_DQ<24>
  134  VSS59  POWER  = GND
  135  DQ25_B  BI  = M_C_CPU0_SB_DQ<25>
  136  VSS60  POWER  = GND
  137  DQS3_B_T  BI  = M_C_CPU0_SB_DQS_DP<3>
  138  DQS3_B_C  BI  = M_C_CPU0_SB_DQS_DN<3>
  139  VSS61  POWER  = GND
  140  DQ28_B  BI  = M_C_CPU0_SB_DQ<28>
  141  VSS62  POWER  = GND
  142  DQ29_B  BI  = M_C_CPU0_SB_DQ<29>
  143  VSS63  POWER  = GND
  144  RFU1  TRI  = TP_CHC_CPU0_DIMM1_FRU_1
  145  VIN_BULK1  POWER  = P12V_S3_AUX_CPU0_NVDIMM
  146  VIN_BULK2  POWER  = P12V_S3_AUX_CPU0_NVDIMM
  147  \pwr_good||fail_n\  BI  = PWRGD_CHC_CPU0_DIMM1
  148  HSA  IN  = PD_CHC_CPU0_DIMM1_SAA
  149  RFU2  TRI  = TP_CHC_CPU0_DIMM1_FRU_2
  150  RFU3  TRI  = TP_CHC_CPU0_DIMM1_FRU_3
  151  VSS64  POWER  = GND
  152  DQ2_A  BI  = M_C_CPU0_SA_DQ<2>
  153  VSS65  POWER  = GND
  154  DQ3_A  BI  = M_C_CPU0_SA_DQ<3>
  155  VSS66  POWER  = GND
  156  \dqs5_a_c||tdqs5_a_c||dqs5_a_t||tdqs5_a_t\  BI  = M_C_CPU0_SA_DQS_DN<5>
  157  \dqs5_a_t||tdqs5_a_t\  BI  = M_C_CPU0_SA_DQS_DP<5>
  158  VSS67  POWER  = GND
  159  DQ6_A  BI  = M_C_CPU0_SA_DQ<6>
  160  VSS68  POWER  = GND
  161  DQ7_A  BI  = M_C_CPU0_SA_DQ<7>
  162  VSS69  POWER  = GND
  163  DQ10_A  BI  = M_C_CPU0_SA_DQ<10>
  164  VSS70  POWER  = GND
  165  DQ11_A  BI  = M_C_CPU0_SA_DQ<11>
  166  VSS71  POWER  = GND
  167  \dqs6_a_c||tdqs6_a_c||dqs6_a_t||tdqs6_a_t\  BI  = M_C_CPU0_SA_DQS_DN<6>
  168  \dqs6_a_t||tdqs6_a_t\  BI  = M_C_CPU0_SA_DQS_DP<6>
  169  VSS72  POWER  = GND
  170  DQ14_A  BI  = M_C_CPU0_SA_DQ<14>
  171  VSS73  POWER  = GND
  172  DQ15_A  BI  = M_C_CPU0_SA_DQ<15>
  173  VSS74  POWER  = GND
  174  DQ18_A  BI  = M_C_CPU0_SA_DQ<18>
  175  VSS75  POWER  = GND
  176  DQ19_A  BI  = M_C_CPU0_SA_DQ<19>
  177  VSS76  POWER  = GND
  178  \dqs7_a_c||tdqs7_a_c\  BI  = M_C_CPU0_SA_DQS_DN<7>
  179  \dqs7_a_t||tdqs7_a_t\  BI  = M_C_CPU0_SA_DQS_DP<7>
  180  VSS77  POWER  = GND
  181  DQ22_A  BI  = M_C_CPU0_SA_DQ<22>
  182  VSS78  POWER  = GND
  183  DQ23_A  BI  = M_C_CPU0_SA_DQ<23>
  184  VSS79  POWER  = GND
  185  DQ26_A  BI  = M_C_CPU0_SA_DQ<26>
  186  VSS80  POWER  = GND
  187  DQ27_A  BI  = M_C_CPU0_SA_DQ<27>
  188  VSS81  POWER  = GND
  189  \dqs8_a_c||tdqs8_a_c\  BI  = M_C_CPU0_SA_DQS_DN<8>
  190  \dqs8_a_t||tdqs8_a_t\  BI  = M_C_CPU0_SA_DQS_DP<8>
  191  VSS82  POWER  = GND
  192  DQ30_A  BI  = M_C_CPU0_SA_DQ<30>
  193  VSS83  POWER  = GND
  194  DQ31_A  BI  = M_C_CPU0_SA_DQ<31>
  195  VSS84  POWER  = GND
  196  CB2_A  BI  = M_C_CPU0_SA_CB<2>
  197  VSS85  POWER  = GND
  198  CB3_A  BI  = M_C_CPU0_SA_CB<3>
  199  VSS86  POWER  = GND
  200  \dqs9_a_c||tdqs9_a_c\  BI  = M_C_CPU0_SA_DQS_DN<9>
  201  \dqs9_a_t||tdqs9_a_t\  BI  = M_C_CPU0_SA_DQS_DP<9>
  202  VSS87  POWER  = GND
  203  CB6_A  BI  = M_C_CPU0_SA_CB<6>
  204  VSS88  POWER  = GND
  205  CB7_A  BI  = M_C_CPU0_SA_CB<7>
  206  VSS89  POWER  = GND
  207  RESET_N  IN  = RST_M_CD_CPU0_FPGA_N
  208  VSS90  POWER  = GND
  209  CS1_A_N  IN  = M_C_CPU0_SA_CS_N<1>
  210  VSS91  POWER  = GND
  211  CA1_A  IN  = M_C_CPU0_SA_CA<1>
  212  VSS92  POWER  = GND
  213  CA3_A  IN  = M_C_CPU0_SA_CA<3>
  214  VSS93  POWER  = GND
  215  CA5_A  IN  = M_C_CPU0_SA_CA<5>
  216  VSS94  POWER  = GND
  217  CK_T  IN  = M_C_CPU0_CLK_DP<0>
  218  CK_C  IN  = M_C_CPU0_CLK_DN<0>
  219  VSS95  POWER  = GND
  220  RFU4  TRI  = TP_CHC_CPU0_DIMM1_FRU_4
  221  CA1_B  IN  = M_C_CPU0_SB_CA<1>
  222  VSS96  POWER  = GND
  223  CA3_B  IN  = M_C_CPU0_SB_CA<3>
  224  VSS97  POWER  = GND
  225  CA5_B  IN  = M_C_CPU0_SB_CA<5>
  226  VSS98  POWER  = GND
  227  PAR_B  IN  = M_C_CPU0_SB_PAR
  228  VSS99  POWER  = GND
  229  CS1_B_N  IN  = M_C_CPU0_SB_CS_N<1>
  230  VSS100  POWER  = GND
  231  RFU5  TRI  = TP_CHC_CPU0_DIMM1_FRU_5
  232  RFU6  TRI  = TP_CHC_CPU0_DIMM1_FRU_6
  233  VSS101  POWER  = GND
  234  CB6_B  BI  = M_C_CPU0_SB_CB<6>
  235  VSS102  POWER  = GND
  236  CB7_B  BI  = M_C_CPU0_SB_CB<7>
  237  VSS103  POWER  = GND
  238  DQS4_B_C  BI  = M_C_CPU0_SB_DQS_DN<4>
  239  DQS4_B_T  BI  = M_C_CPU0_SB_DQS_DP<4>
  240  VSS104  POWER  = GND
  241  CB2_B  BI  = M_C_CPU0_SB_CB<2>
  242  VSS105  POWER  = GND
  243  CB3_B  BI  = M_C_CPU0_SB_CB<3>
  244  VSS106  POWER  = GND
  245  DQ2_B  BI  = M_C_CPU0_SB_DQ<2>
  246  VSS107  POWER  = GND
  247  DQ3_B  BI  = M_C_CPU0_SB_DQ<3>
  248  VSS108  POWER  = GND
  249  \dqs5_b_c||tdqs5_b_c\  BI  = M_C_CPU0_SB_DQS_DN<5>
  250  \dqs5_b_t||tdqs5_b_t\  BI  = M_C_CPU0_SB_DQS_DP<5>
  251  VSS109  POWER  = GND
  252  DQ6_B  BI  = M_C_CPU0_SB_DQ<6>
  253  VSS110  POWER  = GND
  254  DQ7_B  BI  = M_C_CPU0_SB_DQ<7>
  255  VSS111  POWER  = GND
  256  DQ10_B  BI  = M_C_CPU0_SB_DQ<10>
  257  VSS112  POWER  = GND
  258  DQ11_B  BI  = M_C_CPU0_SB_DQ<11>
  259  VSS113  POWER  = GND
  260  \dqs6_b_c||tdqs6_b_c\  BI  = M_C_CPU0_SB_DQS_DN<6>
  261  \dqs6_b_t||tdqs6_b_t\  BI  = M_C_CPU0_SB_DQS_DP<6>
  262  VSS114  POWER  = GND
  263  DQ14_B  BI  = M_C_CPU0_SB_DQ<14>
  264  VSS115  POWER  = GND
  265  DQ15_B  BI  = M_C_CPU0_SB_DQ<15>
  266  VSS116  POWER  = GND
  267  DQ18_B  BI  = M_C_CPU0_SB_DQ<18>
  268  VSS117  POWER  = GND
  269  DQ19_B  BI  = M_C_CPU0_SB_DQ<19>
  270  VSS118  POWER  = GND
  271  \dqs7_b_c||tdqs7_b_c\  BI  = M_C_CPU0_SB_DQS_DN<7>
  272  \dqs7_b_t||tdqs7_b_t\  BI  = M_C_CPU0_SB_DQS_DP<7>
  273  VSS119  POWER  = GND
  274  DQ22_B  BI  = M_C_CPU0_SB_DQ<22>
  275  VSS120  POWER  = GND
  276  DQ23_B  BI  = M_C_CPU0_SB_DQ<23>
  277  VSS121  POWER  = GND
  278  DQ26_B  BI  = M_C_CPU0_SB_DQ<26>
  279  VSS122  POWER  = GND
  280  DQ27_B  BI  = M_C_CPU0_SB_DQ<27>
  281  VSS123  POWER  = GND
  282  \dqs8_b_c||tdqs8_b_c\  BI  = M_C_CPU0_SB_DQS_DN<8>
  283  \dqs8_b_t||tdqs8_b_t\  BI  = M_C_CPU0_SB_DQS_DP<8>
  284  VSS124  POWER  = GND
  285  DQ30_B  BI  = M_C_CPU0_SB_DQ<30>
  286  VSS125  POWER  = GND
  287  DQ31_B  BI  = M_C_CPU0_SB_DQ<31>
  288  VSS126  POWER  = GND
  G1  G1  POWER  = GND
  G2  G2  POWER  = GND
  G3  G3  POWER  = GND
